FILE_TYPE = MACRO_DRAWING;
SET COLOR_WIRE YELLOW;
SET COLOR_PROP ORANGE;
SET COLOR_DOT WHITE;
SET COLOR_ARC YELLOW;
SET COLOR_BODY GREEN;
SET COLOR_NOTE PURPLE;
SET PROP_DISPLAY VALUE;
SET PAGE_NUMBER P172;
FORCEADD QUANTA_TITLE_BLOCK_C..1
(0 0);
FORCEPROP 1 LAST CUSTOM_TXT_CDS <NAME_2>
J 0
(-3175 50);
FORCEPROP 1 LAST CUSTOM_TXT_CDS <NAME_1>
J 0
(-3175 175);
FORCEPROP 1 LAST CUSTOM_TXT_CDS <Q_NUMBER>
J 0
(-1403 103);
DISPLAY 1.212766 (-1403 103);
FORCEPROP 1 LAST CUSTOM_TXT_CDS <Q_PROJ>
J 0
(-2382 102);
DISPLAY 1.212766 (-2382 102);
FORCEPROP 1 LAST CUSTOM_TXT_CDS <Q_REV>
J 0
(-184 103);
DISPLAY 1.212766 (-184 103);
FORCEPROP 1 LAST CUSTOM_TXT_CDS <CON_LAST_MODIFIED>
J 0
(-1885 15);
DISPLAY 0.978723 (-1885 15);
FORCEPROP 1 LAST CUSTOM_TXT_CDS <CON_PAGE_NUM> OF <CON_TOTAL_PAGES>
J 0
(-446 18);
DISPLAY 0.978723 (-446 18);
FORCEPROP 1 LAST Q_TITLE Blank
J 0
(-9366 26);
DISPLAY 2.446809 (-9366 26);
PAINT GREEN (-9366 26);
FORCEPROP 2 LAST PAGE_BORDER TRUE
J 0
(-7890 5250);
DISPLAY 0.638298 (-7890 5250);
PAINT PINK (-7890 5250);
DISPLAY INVISIBLE (-7890 5250);
FORCEPROP 2 LAST CDS_LIB pure_quanta
J 0
(0 0);
DISPLAY INVISIBLE (0 0);
FORCEPROP 1 LAST CDS_LMAN_SYM_OUTLINE -9475,6775,100,-125
J 0
(0 0);
DISPLAY 0.468085 (0 0);
PAINT GREEN (0 0);
DISPLAY INVISIBLE (0 0);
FORCEPROP 2 LAST CDS_XR_PAGE_TITLE CR-197 : @T6G_MB_LIB.T6G(SCH_1):PAGE197
J 0
(-7890 5250);
DISPLAY 0.638298 (-7890 5250);
PAINT PINK (-7890 5250);
DISPLAY INVISIBLE (-7890 5250);
FORCEPROP 2 LAST CUSTOM_TXT_CDS <XR_PAGE_TITLE>
J 0
(-7890 5250);
DISPLAY 0.638298 (-7890 5250);
PAINT PINK (-7890 5250);
DISPLAY INVISIBLE (-7890 5250);
FORCEPROP 1 LAST COMMENT_BODY TRUE
J 0
(12 -13);
DISPLAY 0.978723 (12 -13);
PAINT GREEN (12 -13);
DISPLAY INVISIBLE (12 -13);
FORCEPROP 1 LAST Q_DEPT BU9
J 1
(-3763 49);
DISPLAY 1.957447 (-3763 49);
PAINT GREEN (-3763 49);
DISPLAY INVISIBLE (-3763 49);
FORCEPROP 0 LAST CDS_CON_LAST_MODIFIED Thu Aug 24 10:15:08 2023
J 0
(-1885 15);
DISPLAY INVISIBLE (-1885 15);
QUIT
